# T6G (Grand Teton) — schematic netlist excerpt (pin names and nets, part order shuffled) for the footprints in the layout excerpt that follows; sources: Cadence DE-HDL packaged netlist, KiCad conversion of 04192023_DAF0TMB3IC0_F0TG_MB_C_brd_V02_OCP.brd

R741  Q_RES  1K 1% EMPTY  pkg 0201LF  page 331 : A = RT_CPU1_P1_ADDR3 ; B = GND
PC545_4  Q_CAP  0.1UF 25V 10% X7R  pkg 0402  page 195 : A = PVDDCR_CPU0_P0_VCCS ; B = GND
PC371_C1P1_1  Q_CAP  2.2UF 10V 10% X6S  pkg C0402  page 218 : A = PVDDCR_CPU1_P1_PVCC ; B = GND

(kicad_pcb
	(version 20260206)
	(generator "pcbnew")
	(generator_version "10.0")
	(general
		(thickness 1.6)
		(legacy_teardrops no)
	)
	(paper "A4")
	(title_block
		(title "04192023_DAF0TMB3IC0_F0TG_MB_C_brd_V02_OCP.brd")
		(comment 1 "Grand Teton / footprints 938-940 of 8354")
	)
	(layers
		(0 "F.Cu" signal "TOP")
		(4 "In1.Cu" signal "GND")
		(6 "In2.Cu" signal "IN1")
		(8 "In3.Cu" signal "GND1")
		(10 "In4.Cu" signal "IN2")
		(12 "In5.Cu" signal "GND2")
		(14 "In6.Cu" signal "IN3")
		(16 "In7.Cu" signal "GND3")
		(18 "In8.Cu" signal "VCC")
		(20 "In9.Cu" signal "VCC1")
		(22 "In10.Cu" signal "GND4")
		(24 "In11.Cu" signal "IN4")
		(26 "In12.Cu" signal "GND5")
		(28 "In13.Cu" signal "IN5")
		(30 "In14.Cu" signal "GND6")
		(32 "In15.Cu" signal "IN6")
		(34 "In16.Cu" signal "GND7")
		(2 "B.Cu" signal "BOTTOM")
		(9 "F.Adhes" user "F.Adhesive")
		(11 "B.Adhes" user "B.Adhesive")
		(13 "F.Paste" user "Package Geometry/Pastemask Top")
		(15 "B.Paste" user "Package Geometry/Pastemask Bottom")
		(5 "F.SilkS" user "Ref Des/Silkscreen Top")
		(7 "B.SilkS" user "Ref Des/Silkscreen Bottom")
		(1 "F.Mask" user "Board Geometry/Soldermask Top")
		(3 "B.Mask" user "Board Geometry/Soldermask Bottom")
		(17 "Dwgs.User" user "User.Drawings")
		(19 "Cmts.User" user "User.Comments")
		(21 "Eco1.User" user "User.Eco1")
		(23 "Eco2.User" user "User.Eco2")
		(25 "Edge.Cuts" user "Board Geometry/Outline")
		(27 "Margin" user)
		(31 "F.CrtYd" user "Package Geometry/Place Bound Top")
		(29 "B.CrtYd" user "Package Geometry/Place Bound Bottom")
		(35 "F.Fab" user "Ref Des/Assembly Top")
		(33 "B.Fab" user "Ref Des/Assembly Bottom")
	)
	(footprint ""
		(layer "F.Cu")
		(at 104.409748 -386.7912 90)
		(property "Reference" "R741"
			(at 0 0 90)
			(layer "F.SilkS")
			(hide yes)
			(effects
				(font
					(size 1.27 1.27)
				)
			)
		)
		(property "Value" ""
			(at 0 0 90)
			(layer "F.Fab")
			(effects
				(font
					(size 1.27 1.27)
				)
			)
		)
		(duplicate_pad_numbers_are_jumpers no)
		(fp_line
			(start 0.32512 -0.175006)
			(end 0.32512 0.175006)
			(stroke
				(width 0.1)
				(type default)
			)
			(layer "F.Fab")
		)
		(fp_line
			(start -0.32512 -0.175006)
			(end 0.32512 -0.175006)
			(stroke
				(width 0.1)
				(type default)
			)
			(layer "F.Fab")
		)
		(fp_line
			(start 0.32512 0.175006)
			(end -0.32512 0.175006)
			(stroke
				(width 0.1)
				(type default)
			)
			(layer "F.Fab")
		)
		(fp_line
			(start -0.32512 0.175006)
			(end -0.32512 -0.175006)
			(stroke
				(width 0.1)
				(type default)
			)
			(layer "F.Fab")
		)
		(pad "1" smd rect
			(at -0.2667 0 90)
			(size 0.3048 0.381)
			(layers "F.Cu" "F.Mask" "F.Paste")
			(net "RT_CPU1_P1_ADDR3")
		)
		(pad "2" smd rect
			(at 0.2667 0 270)
			(size 0.3048 0.381)
			(layers "F.Cu" "F.Mask" "F.Paste")
			(net "GND")
		)
	)
	(footprint ""
		(layer "F.Cu")
		(at 83.439254 -334.976724 -90)
		(property "Reference" "PC371_C1P1_1"
			(at 0 0 270)
			(layer "F.SilkS")
			(hide yes)
			(effects
				(font
					(size 1.27 1.27)
				)
			)
		)
		(property "Value" ""
			(at 0 0 270)
			(layer "F.Fab")
			(effects
				(font
					(size 1.27 1.27)
				)
			)
		)
		(duplicate_pad_numbers_are_jumpers no)
		(fp_line
			(start -0.7874 0.4064)
			(end -0.7874 -0.4064)
			(stroke
				(width 0.1524)
				(type default)
			)
			(layer "F.SilkS")
		)
		(fp_line
			(start 0.7874 0.4064)
			(end -0.7874 0.4064)
			(stroke
				(width 0.1524)
				(type default)
			)
			(layer "F.SilkS")
		)
		(fp_line
			(start -0.7874 -0.4064)
			(end 0.7874 -0.4064)
			(stroke
				(width 0.1524)
				(type default)
			)
			(layer "F.SilkS")
		)
		(fp_line
			(start 0.7874 -0.4064)
			(end 0.7874 0.4064)
			(stroke
				(width 0.1524)
				(type default)
			)
			(layer "F.SilkS")
		)
		(fp_line
			(start -0.67945 0.3048)
			(end -0.67945 -0.305054)
			(stroke
				(width 0.1)
				(type default)
			)
			(layer "F.Fab")
		)
		(fp_line
			(start -0.12065 0.3048)
			(end -0.67945 0.3048)
			(stroke
				(width 0.1)
				(type default)
			)
			(layer "F.Fab")
		)
		(fp_line
			(start 0.120396 0.3048)
			(end 0.120396 0.2794)
			(stroke
				(width 0.1)
				(type default)
			)
			(layer "F.Fab")
		)
		(fp_line
			(start 0.67945 0.3048)
			(end 0.120396 0.3048)
			(stroke
				(width 0.1)
				(type default)
			)
			(layer "F.Fab")
		)
		(fp_line
			(start -0.12065 0.2794)
			(end -0.12065 0.3048)
			(stroke
				(width 0.1)
				(type default)
			)
			(layer "F.Fab")
		)
		(fp_line
			(start 0.120396 0.2794)
			(end -0.12065 0.2794)
			(stroke
				(width 0.1)
				(type default)
			)
			(layer "F.Fab")
		)
		(fp_line
			(start -0.12065 -0.2794)
			(end 0.12065 -0.2794)
			(stroke
				(width 0.1)
				(type default)
			)
			(layer "F.Fab")
		)
		(fp_line
			(start 0.12065 -0.2794)
			(end 0.12065 -0.3048)
			(stroke
				(width 0.1)
				(type default)
			)
			(layer "F.Fab")
		)
		(fp_line
			(start 0.12065 -0.3048)
			(end 0.67945 -0.3048)
			(stroke
				(width 0.1)
				(type default)
			)
			(layer "F.Fab")
		)
		(fp_line
			(start 0.67945 -0.3048)
			(end 0.67945 0.3048)
			(stroke
				(width 0.1)
				(type default)
			)
			(layer "F.Fab")
		)
		(fp_line
			(start -0.67945 -0.305054)
			(end -0.12065 -0.305054)
			(stroke
				(width 0.1)
				(type default)
			)
			(layer "F.Fab")
		)
		(fp_line
			(start -0.12065 -0.305054)
			(end -0.12065 -0.2794)
			(stroke
				(width 0.1)
				(type default)
			)
			(layer "F.Fab")
		)
		(pad "1" smd circle
			(at -0.40005 0 270)
			(size 0 0)
			(layers "F.Cu" "F.Mask" "F.Paste")
			(net "PVDDCR_CPU1_P1_PVCC")
		)
		(pad "2" smd circle
			(at 0.40005 0 270)
			(size 0 0)
			(layers "F.Cu" "F.Mask" "F.Paste")
			(net "GND")
		)
	)
	(footprint ""
		(layer "F.Cu")
		(at 392.103102 -177.88636 -90)
		(property "Reference" "PC545_4"
			(at 0 0 270)
			(layer "F.SilkS")
			(hide yes)
			(effects
				(font
					(size 1.27 1.27)
				)
			)
		)
		(property "Value" ""
			(at 0 0 270)
			(layer "F.Fab")
			(effects
				(font
					(size 1.27 1.27)
				)
			)
		)
		(duplicate_pad_numbers_are_jumpers no)
		(fp_line
			(start -0.7874 0.4064)
			(end -0.7874 -0.4064)
			(stroke
				(width 0.1524)
				(type default)
			)
			(layer "F.SilkS")
		)
		(fp_line
			(start 0.7874 0.4064)
			(end -0.7874 0.4064)
			(stroke
				(width 0.1524)
				(type default)
			)
			(layer "F.SilkS")
		)
		(fp_line
			(start -0.7874 -0.4064)
			(end 0.7874 -0.4064)
			(stroke
				(width 0.1524)
				(type default)
			)
			(layer "F.SilkS")
		)
		(fp_line
			(start 0.7874 -0.4064)
			(end 0.7874 0.4064)
			(stroke
				(width 0.1524)
				(type default)
			)
			(layer "F.SilkS")
		)
		(fp_line
			(start -0.67945 0.3048)
			(end -0.67945 -0.305054)
			(stroke
				(width 0.1)
				(type default)
			)
			(layer "F.Fab")
		)
		(fp_line
			(start -0.12065 0.3048)
			(end -0.67945 0.3048)
			(stroke
				(width 0.1)
				(type default)
			)
			(layer "F.Fab")
		)
		(fp_line
			(start 0.120396 0.3048)
			(end 0.120396 0.2794)
			(stroke
				(width 0.1)
				(type default)
			)
			(layer "F.Fab")
		)
		(fp_line
			(start 0.67945 0.3048)
			(end 0.120396 0.3048)
			(stroke
				(width 0.1)
				(type default)
			)
			(layer "F.Fab")
		)
		(fp_line
			(start -0.12065 0.2794)
			(end -0.12065 0.3048)
			(stroke
				(width 0.1)
				(type default)
			)
			(layer "F.Fab")
		)
		(fp_line
			(start 0.120396 0.2794)
			(end -0.12065 0.2794)
			(stroke
				(width 0.1)
				(type default)
			)
			(layer "F.Fab")
		)
		(fp_line
			(start -0.12065 -0.2794)
			(end 0.12065 -0.2794)
			(stroke
				(width 0.1)
				(type default)
			)
			(layer "F.Fab")
		)
		(fp_line
			(start 0.12065 -0.2794)
			(end 0.12065 -0.3048)
			(stroke
				(width 0.1)
				(type default)
			)
			(layer "F.Fab")
		)
		(fp_line
			(start 0.12065 -0.3048)
			(end 0.67945 -0.3048)
			(stroke
				(width 0.1)
				(type default)
			)
			(layer "F.Fab")
		)
		(fp_line
			(start 0.67945 -0.3048)
			(end 0.67945 0.3048)
			(stroke
				(width 0.1)
				(type default)
			)
			(layer "F.Fab")
		)
		(fp_line
			(start -0.67945 -0.305054)
			(end -0.12065 -0.305054)
			(stroke
				(width 0.1)
				(type default)
			)
			(layer "F.Fab")
		)
		(fp_line
			(start -0.12065 -0.305054)
			(end -0.12065 -0.2794)
			(stroke
				(width 0.1)
				(type default)
			)
			(layer "F.Fab")
		)
		(pad "1" smd circle
			(at -0.40005 0 270)
			(size 0 0)
			(layers "F.Cu" "F.Mask" "F.Paste")
			(net "PVDDCR_CPU0_P0_VCCS")
		)
		(pad "2" smd circle
			(at 0.40005 0 270)
			(size 0 0)
			(layers "F.Cu" "F.Mask" "F.Paste")
			(net "GND")
		)
	)
)
